# TIMECARD (Time Appliance Project (Time Card)) — schematic netlist excerpt (pin names and nets, part order shuffled) for the footprints in the layout excerpt that follows; sources: Cadence DE-HDL packaged netlist, KiCad conversion of R4006-B0001-02_R01.brd

TP58  TP_PIONT  pkg TP010CT020B030_PTH  page 25 : \1\ = XP3R3V_FPGA
MAC_PIN3  NUT  pkg P_NUT_079C100  page 21 : \1\ = R_MAC_10MHZ_RF_OUT
TP138  TP_PIONT  pkg TP010CT020B030_PTH  page 25 : \1\ = IO_L23P_34

(kicad_pcb
	(version 20260206)
	(generator "pcbnew")
	(generator_version "10.0")
	(general
		(thickness 1.6)
		(legacy_teardrops no)
	)
	(paper "A4")
	(title_block
		(title "timecard-production-celestica-r4006 — R4006-B0001-02_R01.brd")
		(comment 1 "Time Appliance Project (Time Card) / footprints 286-288 of 1113")
	)
	(layers
		(0 "F.Cu" signal "TOP")
		(4 "In1.Cu" signal "L02_GND1")
		(6 "In2.Cu" signal "L03_SIG1")
		(8 "In3.Cu" signal "L04_GND2")
		(10 "In4.Cu" signal "L05_VCC1")
		(12 "In5.Cu" signal "L06_VCC2")
		(14 "In6.Cu" signal "L07_GND3")
		(16 "In7.Cu" signal "L08_SIG2")
		(18 "In8.Cu" signal "L09_GND4")
		(2 "B.Cu" signal "BOTTOM")
		(9 "F.Adhes" user "F.Adhesive")
		(11 "B.Adhes" user "B.Adhesive")
		(13 "F.Paste" user "Package Geometry/Pastemask Top")
		(15 "B.Paste" user "Package Geometry/Pastemask Bottom")
		(5 "F.SilkS" user "Ref Des/Silkscreen Top")
		(7 "B.SilkS" user "Ref Des/Silkscreen Bottom")
		(1 "F.Mask" user "Board Geometry/Soldermask Top")
		(3 "B.Mask" user "Board Geometry/Soldermask Bottom")
		(17 "Dwgs.User" user "User.Drawings")
		(19 "Cmts.User" user "User.Comments")
		(21 "Eco1.User" user "User.Eco1")
		(23 "Eco2.User" user "User.Eco2")
		(25 "Edge.Cuts" user "Board Geometry/Outline")
		(27 "Margin" user)
		(31 "F.CrtYd" user "Package Geometry/Place Bound Top")
		(29 "B.CrtYd" user "Package Geometry/Place Bound Bottom")
		(35 "F.Fab" user "Ref Des/Assembly Top")
		(33 "B.Fab" user "Ref Des/Assembly Bottom")
	)
	(footprint ""
		(layer "F.Cu")
		(at 32.021018 -26.426922)
		(property "Reference" "MAC_PIN3"
			(at -2.176018 -2.621026 0)
			(unlocked yes)
			(layer "F.SilkS")
			(effects
				(font
					(size 0.7874 0.5842)
					(thickness 0.1524)
				)
			)
		)
		(property "Value" ""
			(at 0 0 0)
			(layer "F.Fab")
			(effects
				(font
					(size 1.27 1.27)
				)
			)
		)
		(property "User Part Number" "PARTNUM*"
			(at 0 3.826764 0)
			(unlocked yes)
			(layer "Cmts.User")
			(hide yes)
			(effects
				(font
					(size 0.7874 0.5842)
					(thickness 0.1524)
				)
			)
		)
		(property "Device Type" "NUT-A200-00029-FB"
			(at 0 2.632964 0)
			(unlocked yes)
			(layer "F.Fab")
			(hide yes)
			(effects
				(font
					(size 0.7874 0.5842)
					(thickness 0.1524)
				)
			)
		)
		(duplicate_pad_numbers_are_jumpers no)
		(fp_circle
			(center 0 0)
			(end 1.524 0)
			(stroke
				(width 0.1)
				(type default)
			)
			(fill no)
			(layer "F.SilkS")
		)
		(fp_poly
			(pts
				(arc
					(start -1.260856 -0.1524)
					(mid -0.898049 -0.898049)
					(end -0.1524 -1.260856)
				)
				(arc
					(start -0.1524 -0.991616)
					(mid -0.709411 -0.709411)
					(end -0.991616 -0.1524)
				)
			)
			(stroke
				(width 0)
				(type default)
			)
			(fill yes)
			(layer "F.Paste")
		)
		(fp_poly
			(pts
				(arc
					(start -0.1524 1.260856)
					(mid -0.898049 0.898049)
					(end -1.260856 0.1524)
				)
				(arc
					(start -0.991616 0.1524)
					(mid -0.709411 0.709411)
					(end -0.1524 0.991616)
				)
			)
			(stroke
				(width 0)
				(type default)
			)
			(fill yes)
			(layer "F.Paste")
		)
		(fp_poly
			(pts
				(arc
					(start 0.1524 -1.260856)
					(mid 0.898049 -0.898049)
					(end 1.260856 -0.1524)
				)
				(arc
					(start 0.991616 -0.1524)
					(mid 0.709411 -0.709411)
					(end 0.1524 -0.991616)
				)
			)
			(stroke
				(width 0)
				(type default)
			)
			(fill yes)
			(layer "F.Paste")
		)
		(fp_poly
			(pts
				(arc
					(start 1.260856 0.1524)
					(mid 0.898049 0.898049)
					(end 0.1524 1.260856)
				)
				(arc
					(start 0.1524 0.991616)
					(mid 0.709411 0.709411)
					(end 0.991616 0.1524)
				)
			)
			(stroke
				(width 0)
				(type default)
			)
			(fill yes)
			(layer "F.Paste")
		)
		(fp_poly
			(pts
				(arc
					(start 6.35 0)
					(mid -6.35 0)
					(end 6.35 0)
				)
			)
			(stroke
				(width 0)
				(type default)
			)
			(fill no)
			(layer "B.CrtYd")
		)
		(fp_poly
			(pts
				(arc
					(start 1.778 0)
					(mid -1.778 0)
					(end 1.778 0)
				)
			)
			(stroke
				(width 0)
				(type default)
			)
			(fill no)
			(layer "F.CrtYd")
		)
		(fp_circle
			(center 0 0)
			(end 1.1684 0)
			(stroke
				(width 0.1)
				(type default)
			)
			(fill no)
			(layer "F.Fab")
		)
		(pad "1" thru_hole circle
			(at 0 0)
			(size 2.54 2.54)
			(drill 2.0066)
			(layers "*.Cu" "*.Mask")
			(remove_unused_layers no)
			(net "R_MAC_10MHZ_RF_OUT")
			(thermal_gap 0.0254)
			(padstack
				(mode front_inner_back)
				(layer "Inner"
					(shape circle)
					(size 2.54 2.54)
					(clearance 0.0254)
				)
				(layer "B.Cu"
					(shape circle)
					(size 2.54 2.54)
				)
			)
		)
	)
	(footprint ""
		(layer "F.Cu")
		(at 127.889 -37.846)
		(property "Reference" "TP138"
			(at 2.26695 2.3749 90)
			(unlocked yes)
			(layer "F.SilkS")
			(effects
				(font
					(size 0.635 0.4064)
					(thickness 0.1524)
				)
				(justify left)
			)
		)
		(property "Value" ""
			(at 0 0 0)
			(layer "F.Fab")
			(effects
				(font
					(size 1.27 1.27)
				)
			)
		)
		(property "Device Type" "TP_PIONT-TP010CT020B030_PTH-TPA"
			(at -1.341882 0.996696 0)
			(unlocked yes)
			(layer "F.Fab")
			(hide yes)
			(effects
				(font
					(size 0.7874 0.5842)
					(thickness 0.1524)
				)
				(justify left)
			)
		)
		(duplicate_pad_numbers_are_jumpers no)
		(fp_poly
			(pts
				(arc
					(start 0.889 0)
					(mid -0.889 0)
					(end 0.889 0)
				)
			)
			(stroke
				(width 0)
				(type default)
			)
			(fill no)
			(layer "B.CrtYd")
		)
		(fp_poly
			(pts
				(arc
					(start 0.889 0)
					(mid -0.889 0)
					(end 0.889 0)
				)
			)
			(stroke
				(width 0)
				(type default)
			)
			(fill no)
			(layer "F.CrtYd")
		)
		(pad "1" thru_hole circle
			(at 0 0)
			(size 0.508 0.508)
			(drill 0.254)
			(layers "*.Cu" "*.Mask")
			(remove_unused_layers no)
			(net "IO_L23P_34")
			(clearance 0.1016)
			(padstack
				(mode front_inner_back)
				(layer "Inner"
					(shape circle)
					(size 0.508 0.508)
					(clearance 0.1016)
				)
				(layer "B.Cu"
					(shape circle)
					(size 0.762 0.762)
					(clearance -0.0254)
				)
			)
		)
	)
	(footprint ""
		(layer "F.Cu")
		(at 90.932 -66.421)
		(property "Reference" "TP58"
			(at -1.6764 -1.11125 0)
			(unlocked yes)
			(layer "F.SilkS")
			(effects
				(font
					(size 0.635 0.4064)
					(thickness 0.1524)
				)
				(justify left)
			)
		)
		(property "Value" ""
			(at 0 0 0)
			(layer "F.Fab")
			(effects
				(font
					(size 1.27 1.27)
				)
			)
		)
		(property "Device Type" "TP_PIONT-TP010CT020B030_PTH-TPA"
			(at -1.341882 0.996696 0)
			(unlocked yes)
			(layer "F.Fab")
			(hide yes)
			(effects
				(font
					(size 0.7874 0.5842)
					(thickness 0.1524)
				)
				(justify left)
			)
		)
		(duplicate_pad_numbers_are_jumpers no)
		(fp_poly
			(pts
				(arc
					(start 0.889 0)
					(mid -0.889 0)
					(end 0.889 0)
				)
			)
			(stroke
				(width 0)
				(type default)
			)
			(fill no)
			(layer "B.CrtYd")
		)
		(fp_poly
			(pts
				(arc
					(start 0.889 0)
					(mid -0.889 0)
					(end 0.889 0)
				)
			)
			(stroke
				(width 0)
				(type default)
			)
			(fill no)
			(layer "F.CrtYd")
		)
		(pad "1" thru_hole circle
			(at 0 0)
			(size 0.508 0.508)
			(drill 0.254)
			(layers "*.Cu" "*.Mask")
			(remove_unused_layers no)
			(net "XP3R3V_FPGA")
			(clearance 0.1016)
			(padstack
				(mode front_inner_back)
				(layer "Inner"
					(shape circle)
					(size 0.508 0.508)
					(clearance 0.1016)
				)
				(layer "B.Cu"
					(shape circle)
					(size 0.762 0.762)
					(clearance -0.0254)
				)
			)
		)
	)
)
